(kicad_pcb
	(version 20260206)
	(generator "pcbnew")
	(generator_version "10.0")
	(general
		(thickness 1.6)
		(legacy_teardrops no)
	)
	(paper "A4")
	(title_block
		(title "01162023_DA0F0TEBIF0_F0T_Expander_BD_F_brd_V02_OCP.brd")
		(comment 1 "Grand Teton / footprint 3736 of 9728 (J1), pads 1-48 of 48")
	)
	(layers
		(0 "F.Cu" signal "TOP")
		(4 "In1.Cu" signal "GND")
		(6 "In2.Cu" signal "VCC")
		(8 "In3.Cu" signal "VCC1")
		(10 "In4.Cu" signal "GND1")
		(12 "In5.Cu" signal "IN1")
		(14 "In6.Cu" signal "GND2")
		(16 "In7.Cu" signal "IN2")
		(18 "In8.Cu" signal "GND3")
		(20 "In9.Cu" signal "IN3")
		(22 "In10.Cu" signal "GND4")
		(24 "In11.Cu" signal "IN4")
		(26 "In12.Cu" signal "GND5")
		(28 "In13.Cu" signal "IN5")
		(30 "In14.Cu" signal "GND6")
		(32 "In15.Cu" signal "IN6")
		(34 "In16.Cu" signal "GND7")
		(2 "B.Cu" signal "BOTTOM")
		(9 "F.Adhes" user "F.Adhesive")
		(11 "B.Adhes" user "B.Adhesive")
		(13 "F.Paste" user "Package Geometry/Pastemask Top")
		(15 "B.Paste" user "Package Geometry/Pastemask Bottom")
		(5 "F.SilkS" user "Ref Des/Silkscreen Top")
		(7 "B.SilkS" user "Ref Des/Silkscreen Bottom")
		(1 "F.Mask" user "Board Geometry/Soldermask Top")
		(3 "B.Mask" user "Board Geometry/Soldermask Bottom")
		(17 "Dwgs.User" user "User.Drawings")
		(19 "Cmts.User" user "User.Comments")
		(21 "Eco1.User" user "User.Eco1")
		(23 "Eco2.User" user "User.Eco2")
		(25 "Edge.Cuts" user "Board Geometry/Outline")
		(27 "Margin" user)
		(31 "F.CrtYd" user "Package Geometry/Place Bound Top")
		(29 "B.CrtYd" user "Package Geometry/Place Bound Bottom")
		(35 "F.Fab" user "Ref Des/Assembly Top")
		(33 "B.Fab" user "Ref Des/Assembly Bottom")
	)
	(footprint ""
		(layer "F.Cu")
		(at 261.115048 -412.187898 -90)
		(property "Reference" "J1"
			(at 13.812012 52.36083 0)
			(unlocked yes)
			(layer "F.SilkS")
			(effects
				(font
					(size 2.032 1.524)
					(thickness 0.1524)
				)
			)
		)
		(property "Value" ""
			(at 0 0 270)
			(layer "F.Fab")
			(effects
				(font
					(size 1.27 1.27)
				)
			)
		)
		(duplicate_pad_numbers_are_jumpers no)
		(pad "P1_1" thru_hole rect
			(at 0 0 270)
			(size 1.790954 1.790954)
			(drill 1.015746)
			(layers "*.Cu" "*.Mask")
			(remove_unused_layers no)
			(net "GND")
			(clearance -0.133604)
			(padstack
				(mode front_inner_back)
				(layer "Inner"
					(shape circle)
					(size 1.790954 1.790954)
					(clearance -0.133604)
				)
				(layer "B.Cu"
					(shape rect)
					(size 1.790954 1.790954)
					(clearance -0.133604)
				)
			)
		)
		(pad "P1_2" thru_hole circle
			(at 2.54 0 270)
			(size 1.790954 1.790954)
			(drill 1.015746)
			(layers "*.Cu" "*.Mask")
			(remove_unused_layers no)
			(net "GND")
			(clearance -0.133604)
		)
		(pad "P1_3" thru_hole circle
			(at 5.08 0 270)
			(size 1.790954 1.790954)
			(drill 1.015746)
			(layers "*.Cu" "*.Mask")
			(remove_unused_layers no)
			(net "GND")
			(clearance -0.133604)
		)
		(pad "P1_4" thru_hole circle
			(at 7.62 0 270)
			(size 1.790954 1.790954)
			(drill 1.015746)
			(layers "*.Cu" "*.Mask")
			(remove_unused_layers no)
			(net "GND")
			(clearance -0.133604)
		)
		(pad "P1_5" thru_hole circle
			(at 0 2.54 270)
			(size 1.790954 1.790954)
			(drill 1.015746)
			(layers "*.Cu" "*.Mask")
			(remove_unused_layers no)
			(net "GND")
			(clearance -0.133604)
		)
		(pad "P1_6" thru_hole circle
			(at 2.54 2.54 270)
			(size 1.790954 1.790954)
			(drill 1.015746)
			(layers "*.Cu" "*.Mask")
			(remove_unused_layers no)
			(net "GND")
			(clearance -0.133604)
		)
		(pad "P1_7" thru_hole circle
			(at 5.08 2.54 270)
			(size 1.790954 1.790954)
			(drill 1.015746)
			(layers "*.Cu" "*.Mask")
			(remove_unused_layers no)
			(net "GND")
			(clearance -0.133604)
		)
		(pad "P1_8" thru_hole circle
			(at 7.62 2.54 270)
			(size 1.790954 1.790954)
			(drill 1.015746)
			(layers "*.Cu" "*.Mask")
			(remove_unused_layers no)
			(net "GND")
			(clearance -0.133604)
		)
		(pad "P2_1" thru_hole circle
			(at 0 8.89 270)
			(size 1.790954 1.790954)
			(drill 1.015746)
			(layers "*.Cu" "*.Mask")
			(remove_unused_layers no)
			(net "GND")
			(clearance -0.133604)
		)
		(pad "P2_2" thru_hole circle
			(at 2.54 8.89 270)
			(size 1.790954 1.790954)
			(drill 1.015746)
			(layers "*.Cu" "*.Mask")
			(remove_unused_layers no)
			(net "GND")
			(clearance -0.133604)
		)
		(pad "P2_3" thru_hole circle
			(at 5.08 8.89 270)
			(size 1.790954 1.790954)
			(drill 1.015746)
			(layers "*.Cu" "*.Mask")
			(remove_unused_layers no)
			(net "GND")
			(clearance -0.133604)
		)
		(pad "P2_4" thru_hole circle
			(at 7.62 8.89 270)
			(size 1.790954 1.790954)
			(drill 1.015746)
			(layers "*.Cu" "*.Mask")
			(remove_unused_layers no)
			(net "GND")
			(clearance -0.133604)
		)
		(pad "P2_5" thru_hole circle
			(at 0 11.43 270)
			(size 1.790954 1.790954)
			(drill 1.015746)
			(layers "*.Cu" "*.Mask")
			(remove_unused_layers no)
			(net "GND")
			(clearance -0.133604)
		)
		(pad "P2_6" thru_hole circle
			(at 2.54 11.43 270)
			(size 1.790954 1.790954)
			(drill 1.015746)
			(layers "*.Cu" "*.Mask")
			(remove_unused_layers no)
			(net "GND")
			(clearance -0.133604)
		)
		(pad "P2_7" thru_hole circle
			(at 5.08 11.43 270)
			(size 1.790954 1.790954)
			(drill 1.015746)
			(layers "*.Cu" "*.Mask")
			(remove_unused_layers no)
			(net "GND")
			(clearance -0.133604)
		)
		(pad "P2_8" thru_hole circle
			(at 7.62 11.43 270)
			(size 1.790954 1.790954)
			(drill 1.015746)
			(layers "*.Cu" "*.Mask")
			(remove_unused_layers no)
			(net "GND")
			(clearance -0.133604)
		)
		(pad "P3_1" thru_hole circle
			(at 0 17.78 270)
			(size 1.790954 1.790954)
			(drill 1.015746)
			(layers "*.Cu" "*.Mask")
			(remove_unused_layers no)
			(net "GND")
			(clearance -0.133604)
		)
		(pad "P3_2" thru_hole circle
			(at 2.54 17.78 270)
			(size 1.790954 1.790954)
			(drill 1.015746)
			(layers "*.Cu" "*.Mask")
			(remove_unused_layers no)
			(net "GND")
			(clearance -0.133604)
		)
		(pad "P3_3" thru_hole circle
			(at 5.08 17.78 270)
			(size 1.790954 1.790954)
			(drill 1.015746)
			(layers "*.Cu" "*.Mask")
			(remove_unused_layers no)
			(net "GND")
			(clearance -0.133604)
		)
		(pad "P3_4" thru_hole circle
			(at 7.62 17.78 270)
			(size 1.790954 1.790954)
			(drill 1.015746)
			(layers "*.Cu" "*.Mask")
			(remove_unused_layers no)
			(net "GND")
			(clearance -0.133604)
		)
		(pad "P3_5" thru_hole circle
			(at 0 20.32 270)
			(size 1.790954 1.790954)
			(drill 1.015746)
			(layers "*.Cu" "*.Mask")
			(remove_unused_layers no)
			(net "GND")
			(clearance -0.133604)
		)
		(pad "P3_6" thru_hole circle
			(at 2.54 20.32 270)
			(size 1.790954 1.790954)
			(drill 1.015746)
			(layers "*.Cu" "*.Mask")
			(remove_unused_layers no)
			(net "GND")
			(clearance -0.133604)
		)
		(pad "P3_7" thru_hole circle
			(at 5.08 20.32 270)
			(size 1.790954 1.790954)
			(drill 1.015746)
			(layers "*.Cu" "*.Mask")
			(remove_unused_layers no)
			(net "GND")
			(clearance -0.133604)
		)
		(pad "P3_8" thru_hole circle
			(at 7.62 20.32 270)
			(size 1.790954 1.790954)
			(drill 1.015746)
			(layers "*.Cu" "*.Mask")
			(remove_unused_layers no)
			(net "GND")
			(clearance -0.133604)
		)
		(pad "P4_1" thru_hole circle
			(at 0 26.67 270)
			(size 1.790954 1.790954)
			(drill 1.015746)
			(layers "*.Cu" "*.Mask")
			(remove_unused_layers no)
			(net "P12V_STBY")
			(clearance -0.133604)
		)
		(pad "P4_2" thru_hole circle
			(at 2.54 26.67 270)
			(size 1.790954 1.790954)
			(drill 1.015746)
			(layers "*.Cu" "*.Mask")
			(remove_unused_layers no)
			(net "P12V_STBY")
			(clearance -0.133604)
		)
		(pad "P4_3" thru_hole circle
			(at 5.08 26.67 270)
			(size 1.790954 1.790954)
			(drill 1.015746)
			(layers "*.Cu" "*.Mask")
			(remove_unused_layers no)
			(net "P12V_STBY")
			(clearance -0.133604)
		)
		(pad "P4_4" thru_hole circle
			(at 7.62 26.67 270)
			(size 1.790954 1.790954)
			(drill 1.015746)
			(layers "*.Cu" "*.Mask")
			(remove_unused_layers no)
			(net "P12V_STBY")
			(clearance -0.133604)
		)
		(pad "P4_5" thru_hole circle
			(at 0 29.21 270)
			(size 1.790954 1.790954)
			(drill 1.015746)
			(layers "*.Cu" "*.Mask")
			(remove_unused_layers no)
			(net "P12V_STBY")
			(clearance -0.133604)
		)
		(pad "P4_6" thru_hole circle
			(at 2.54 29.21 270)
			(size 1.790954 1.790954)
			(drill 1.015746)
			(layers "*.Cu" "*.Mask")
			(remove_unused_layers no)
			(net "P12V_STBY")
			(clearance -0.133604)
		)
		(pad "P4_7" thru_hole circle
			(at 5.08 29.21 270)
			(size 1.790954 1.790954)
			(drill 1.015746)
			(layers "*.Cu" "*.Mask")
			(remove_unused_layers no)
			(net "P12V_STBY")
			(clearance -0.133604)
		)
		(pad "P4_8" thru_hole circle
			(at 7.62 29.21 270)
			(size 1.790954 1.790954)
			(drill 1.015746)
			(layers "*.Cu" "*.Mask")
			(remove_unused_layers no)
			(net "P12V_STBY")
			(clearance -0.133604)
		)
		(pad "P5_1" thru_hole circle
			(at 0 35.56 270)
			(size 1.790954 1.790954)
			(drill 1.015746)
			(layers "*.Cu" "*.Mask")
			(remove_unused_layers no)
			(net "P12V_STBY")
			(clearance -0.133604)
		)
		(pad "P5_2" thru_hole circle
			(at 2.54 35.56 270)
			(size 1.790954 1.790954)
			(drill 1.015746)
			(layers "*.Cu" "*.Mask")
			(remove_unused_layers no)
			(net "P12V_STBY")
			(clearance -0.133604)
		)
		(pad "P5_3" thru_hole circle
			(at 5.08 35.56 270)
			(size 1.790954 1.790954)
			(drill 1.015746)
			(layers "*.Cu" "*.Mask")
			(remove_unused_layers no)
			(net "P12V_STBY")
			(clearance -0.133604)
		)
		(pad "P5_4" thru_hole circle
			(at 7.62 35.56 270)
			(size 1.790954 1.790954)
			(drill 1.015746)
			(layers "*.Cu" "*.Mask")
			(remove_unused_layers no)
			(net "P12V_STBY")
			(clearance -0.133604)
		)
		(pad "P5_5" thru_hole circle
			(at 0 38.1 270)
			(size 1.790954 1.790954)
			(drill 1.015746)
			(layers "*.Cu" "*.Mask")
			(remove_unused_layers no)
			(net "P12V_STBY")
			(clearance -0.133604)
		)
		(pad "P5_6" thru_hole circle
			(at 2.54 38.1 270)
			(size 1.790954 1.790954)
			(drill 1.015746)
			(layers "*.Cu" "*.Mask")
			(remove_unused_layers no)
			(net "P12V_STBY")
			(clearance -0.133604)
		)
		(pad "P5_7" thru_hole circle
			(at 5.08 38.1 270)
			(size 1.790954 1.790954)
			(drill 1.015746)
			(layers "*.Cu" "*.Mask")
			(remove_unused_layers no)
			(net "P12V_STBY")
			(clearance -0.133604)
		)
		(pad "P5_8" thru_hole circle
			(at 7.62 38.1 270)
			(size 1.790954 1.790954)
			(drill 1.015746)
			(layers "*.Cu" "*.Mask")
			(remove_unused_layers no)
			(net "P12V_STBY")
			(clearance -0.133604)
		)
		(pad "P6_1" thru_hole circle
			(at 0 44.45 270)
			(size 1.790954 1.790954)
			(drill 1.015746)
			(layers "*.Cu" "*.Mask")
			(remove_unused_layers no)
			(net "P12V_STBY")
			(clearance -0.133604)
		)
		(pad "P6_2" thru_hole circle
			(at 2.54 44.45 270)
			(size 1.790954 1.790954)
			(drill 1.015746)
			(layers "*.Cu" "*.Mask")
			(remove_unused_layers no)
			(net "P12V_STBY")
			(clearance -0.133604)
		)
		(pad "P6_3" thru_hole circle
			(at 5.08 44.45 270)
			(size 1.790954 1.790954)
			(drill 1.015746)
			(layers "*.Cu" "*.Mask")
			(remove_unused_layers no)
			(net "P12V_STBY")
			(clearance -0.133604)
		)
		(pad "P6_4" thru_hole circle
			(at 7.62 44.45 270)
			(size 1.790954 1.790954)
			(drill 1.015746)
			(layers "*.Cu" "*.Mask")
			(remove_unused_layers no)
			(net "P12V_STBY")
			(clearance -0.133604)
		)
		(pad "P6_5" thru_hole circle
			(at 0 46.99 270)
			(size 1.790954 1.790954)
			(drill 1.015746)
			(layers "*.Cu" "*.Mask")
			(remove_unused_layers no)
			(net "P12V_STBY")
			(clearance -0.133604)
		)
		(pad "P6_6" thru_hole circle
			(at 2.54 46.99 270)
			(size 1.790954 1.790954)
			(drill 1.015746)
			(layers "*.Cu" "*.Mask")
			(remove_unused_layers no)
			(net "P12V_STBY")
			(clearance -0.133604)
		)
		(pad "P6_7" thru_hole circle
			(at 5.08 46.99 270)
			(size 1.790954 1.790954)
			(drill 1.015746)
			(layers "*.Cu" "*.Mask")
			(remove_unused_layers no)
			(net "P12V_STBY")
			(clearance -0.133604)
		)
		(pad "P6_8" thru_hole circle
			(at 7.62 46.99 270)
			(size 1.790954 1.790954)
			(drill 1.015746)
			(layers "*.Cu" "*.Mask")
			(remove_unused_layers no)
			(net "P12V_STBY")
			(clearance -0.133604)
		)
	)
)
